FILE_TYPE = MACRO_DRAWING;
SET COLOR_WIRE YELLOW;
SET COLOR_PROP ORANGE;
SET COLOR_DOT WHITE;
SET COLOR_ARC YELLOW;
SET COLOR_BODY GREEN;
SET COLOR_NOTE PURPLE;
SET PROP_DISPLAY VALUE;
SET PAGE_NUMBER P35;
FORCEADD QUANTA_TITLE_BLOCK_C..1
(0 0);
FORCEPROP 1 LAST CUSTOM_TXT_CDS <NAME_2>
J 0
(-3175 50);
FORCEPROP 1 LAST CUSTOM_TXT_CDS <NAME_1>
J 0
(-3175 175);
FORCEPROP 1 LAST CUSTOM_TXT_CDS <Q_NUMBER>
J 0
(-1403 103);
DISPLAY 1.212766 (-1403 103);
FORCEPROP 1 LAST CUSTOM_TXT_CDS <Q_PROJ>
J 0
(-2382 102);
DISPLAY 1.212766 (-2382 102);
FORCEPROP 1 LAST CUSTOM_TXT_CDS <Q_REV>
J 0
(-184 103);
DISPLAY 1.212766 (-184 103);
FORCEPROP 1 LAST CUSTOM_TXT_CDS <CON_LAST_MODIFIED>
J 0
(-1885 15);
DISPLAY 0.978723 (-1885 15);
FORCEPROP 1 LAST CUSTOM_TXT_CDS <CON_PAGE_NUM> OF <CON_TOTAL_PAGES>
J 0
(-446 18);
DISPLAY 0.978723 (-446 18);
FORCEPROP 1 LAST Q_TITLE Blank
J 0
(-9275 100);
DISPLAY 2.446809 (-9275 100);
PAINT GREEN (-9275 100);
FORCEPROP 1 LAST CDS_LMAN_SYM_OUTLINE -9475,6775,100,-125
J 0
(0 0);
DISPLAY 0.468085 (0 0);
PAINT GREEN (0 0);
DISPLAY INVISIBLE (0 0);
FORCEPROP 2 LAST CDS_LIB pure_quanta
J 0
(0 0);
DISPLAY INVISIBLE (0 0);
FORCEPROP 2 LAST PAGE_BORDER TRUE
J 0
(-7890 5250);
DISPLAY 0.638298 (-7890 5250);
PAINT PINK (-7890 5250);
DISPLAY INVISIBLE (-7890 5250);
FORCEPROP 2 LAST CDS_XR_PAGE_TITLE CR-35 : @T6G_MB_LIB.T6G(SCH_1):PAGE35
J 0
(-7890 5250);
DISPLAY 0.638298 (-7890 5250);
PAINT PINK (-7890 5250);
DISPLAY INVISIBLE (-7890 5250);
FORCEPROP 2 LAST CUSTOM_TXT_CDS <XR_PAGE_TITLE>
J 0
(-7890 5250);
DISPLAY 0.638298 (-7890 5250);
PAINT PINK (-7890 5250);
DISPLAY INVISIBLE (-7890 5250);
FORCEPROP 1 LAST COMMENT_BODY TRUE
J 0
(12 -13);
DISPLAY 0.978723 (12 -13);
PAINT GREEN (12 -13);
DISPLAY INVISIBLE (12 -13);
FORCEPROP 1 LAST Q_DEPT BU9
J 1
(-3763 49);
DISPLAY 1.957447 (-3763 49);
PAINT GREEN (-3763 49);
DISPLAY INVISIBLE (-3763 49);
FORCEPROP 0 LAST CDS_CON_LAST_MODIFIED Thu Aug 24 10:13:43 2023
J 0
(-1885 15);
DISPLAY INVISIBLE (-1885 15);
QUIT
